(kicad_pcb
	(version 20260206)
	(generator "pcbnew")
	(generator_version "10.0")
	(general
		(thickness 1.6)
		(legacy_teardrops no)
	)
	(paper "A4")
	(title_block
		(title "Wiwynn_Tioga_Pass_MB.brd")
		(comment 1 "Tioga Pass / footprints 4678-4685 of 4770")
	)
	(layers
		(0 "F.Cu" signal "TOP")
		(4 "In1.Cu" signal "L2GND")
		(6 "In2.Cu" signal "L3")
		(8 "In3.Cu" signal "L4GND")
		(10 "In4.Cu" signal "L5")
		(12 "In5.Cu" signal "L6GND")
		(14 "In6.Cu" signal "L7VCC")
		(16 "In7.Cu" signal "L8VCC")
		(18 "In8.Cu" signal "L9GND")
		(20 "In9.Cu" signal "L10")
		(22 "In10.Cu" signal "L11GND")
		(24 "In11.Cu" signal "L12")
		(26 "In12.Cu" signal "L13GND")
		(2 "B.Cu" signal "BOTTOM")
		(9 "F.Adhes" user "F.Adhesive")
		(11 "B.Adhes" user "B.Adhesive")
		(13 "F.Paste" user "Package Geometry/Pastemask Top")
		(15 "B.Paste" user "Package Geometry/Pastemask Bottom")
		(5 "F.SilkS" user "Ref Des/Silkscreen Top")
		(7 "B.SilkS" user "Ref Des/Silkscreen Bottom")
		(1 "F.Mask" user "Board Geometry/Soldermask Top")
		(3 "B.Mask" user "Board Geometry/Soldermask Bottom")
		(17 "Dwgs.User" user "User.Drawings")
		(19 "Cmts.User" user "User.Comments")
		(21 "Eco1.User" user "User.Eco1")
		(23 "Eco2.User" user "User.Eco2")
		(25 "Edge.Cuts" user "Board Geometry/Outline")
		(27 "Margin" user)
		(31 "F.CrtYd" user "Package Geometry/Place Bound Top")
		(29 "B.CrtYd" user "Package Geometry/Place Bound Bottom")
		(35 "F.Fab" user "Ref Des/Assembly Top")
		(33 "B.Fab" user "Ref Des/Assembly Bottom")
	)
	(footprint ""
		(layer "B.Cu")
		(at 401.412456 -31.000446)
		(property "Reference" "C25W70"
			(at -0.97536 0.76708 90)
			(unlocked yes)
			(layer "B.SilkS")
			(effects
				(font
					(size 0.4064 0.254)
					(thickness 0.1524)
				)
				(justify mirror)
			)
		)
		(property "Value" ""
			(at 0 0 0)
			(layer "B.Fab")
			(effects
				(font
					(size 1.27 1.27)
				)
				(justify mirror)
			)
		)
		(duplicate_pad_numbers_are_jumpers no)
		(fp_poly
			(pts
				(xy 0.4953 -0.2032) (xy -0.4953 -0.2032) (xy -0.4953 1.6002) (xy 0.4953 1.6002)
			)
			(stroke
				(width 0)
				(type default)
			)
			(fill no)
			(layer "B.CrtYd")
		)
		(fp_line
			(start -0.4953 -0.2032)
			(end -0.4953 1.6002)
			(stroke
				(width 0.1)
				(type default)
			)
			(layer "B.Fab")
		)
		(fp_line
			(start -0.4953 1.6002)
			(end 0.4953 1.6002)
			(stroke
				(width 0.1)
				(type default)
			)
			(layer "B.Fab")
		)
		(fp_line
			(start 0.4953 -0.2032)
			(end -0.4953 -0.2032)
			(stroke
				(width 0.1)
				(type default)
			)
			(layer "B.Fab")
		)
		(fp_line
			(start 0.4953 1.6002)
			(end 0.4953 -0.2032)
			(stroke
				(width 0.1)
				(type default)
			)
			(layer "B.Fab")
		)
		(pad "1" smd rect
			(at 0 0 180)
			(size 0.762 0.889)
			(layers "B.Cu" "B.Mask" "B.Paste")
			(net "P3V3_USB2A_ALG")
		)
		(pad "2" smd rect
			(at 0 1.397 180)
			(size 0.762 0.889)
			(layers "B.Cu" "B.Mask" "B.Paste")
			(net "GND")
		)
		(zone
			(layer "B.Cu")
			(hatch none 0.5)
			(connect_pads
				(clearance 0)
			)
			(min_thickness 0.25)
			(keepout
				(tracks not_allowed)
				(vias allowed)
				(pads allowed)
				(copperpour not_allowed)
				(footprints allowed)
			)
			(placement
				(enabled no)
				(sheetname "")
			)
			(fill
				(thermal_gap 0.5)
				(thermal_bridge_width 0.5)
				(island_removal_mode 0)
			)
			(polygon
				(pts
					(xy 401.793456 -30.555946) (xy 401.031456 -30.555946) (xy 401.031456 -30.047946) (xy 401.793456 -30.047946)
				)
			)
		)
	)
	(footprint ""
		(layer "B.Cu")
		(at -2.20726 -119.46636 180)
		(property "Reference" "R9M17"
			(at 0 0 0)
			(layer "B.SilkS")
			(hide yes)
			(effects
				(font
					(size 1.27 1.27)
				)
				(justify mirror)
			)
		)
		(property "Value" ""
			(at 0 0 0)
			(layer "B.Fab")
			(effects
				(font
					(size 1.27 1.27)
				)
				(justify mirror)
			)
		)
		(duplicate_pad_numbers_are_jumpers no)
		(fp_rect
			(start 0.2794 -0.1016)
			(end -0.2794 0.9906)
			(stroke
				(width 0)
				(type default)
			)
			(fill no)
			(layer "B.CrtYd")
		)
		(fp_line
			(start 0.2794 0.9906)
			(end -0.2794 0.9906)
			(stroke
				(width 0.1)
				(type default)
			)
			(layer "B.Fab")
		)
		(fp_line
			(start 0.2794 -0.1016)
			(end 0.2794 0.9906)
			(stroke
				(width 0.1)
				(type default)
			)
			(layer "B.Fab")
		)
		(fp_line
			(start -0.2794 0.9906)
			(end -0.2794 -0.1016)
			(stroke
				(width 0.1)
				(type default)
			)
			(layer "B.Fab")
		)
		(fp_line
			(start -0.2794 -0.1016)
			(end 0.2794 -0.1016)
			(stroke
				(width 0.1)
				(type default)
			)
			(layer "B.Fab")
		)
		(pad "1" smd rect
			(at 0 0)
			(size 0.508 0.508)
			(layers "B.Cu" "B.Mask" "B.Paste")
			(net "P3V3_STBY")
		)
		(pad "2" smd rect
			(at 0 0.889)
			(size 0.508 0.508)
			(layers "B.Cu" "B.Mask" "B.Paste")
			(net "SMB_PEHPCPU1_STBY_LVC3_R_SCL")
		)
		(zone
			(layer "B.Cu")
			(hatch none 0.5)
			(connect_pads
				(clearance 0)
			)
			(min_thickness 0.25)
			(keepout
				(tracks not_allowed)
				(vias allowed)
				(pads allowed)
				(copperpour not_allowed)
				(footprints allowed)
			)
			(placement
				(enabled no)
				(sheetname "")
			)
			(fill
				(thermal_gap 0.5)
				(thermal_bridge_width 0.5)
				(island_removal_mode 0)
			)
			(polygon
				(pts
					(xy -2.46126 -119.72036) (xy -1.95326 -119.72036) (xy -1.95326 -120.10136) (xy -2.46126 -120.10136)
				)
			)
		)
		(zone
			(layer "B.Cu")
			(hatch none 0.5)
			(connect_pads
				(clearance 0)
			)
			(min_thickness 0.25)
			(keepout
				(tracks allowed)
				(vias not_allowed)
				(pads allowed)
				(copperpour not_allowed)
				(footprints allowed)
			)
			(placement
				(enabled no)
				(sheetname "")
			)
			(fill
				(thermal_gap 0.5)
				(thermal_bridge_width 0.5)
				(island_removal_mode 0)
			)
			(polygon
				(pts
					(xy -2.46126 -119.72036) (xy -1.95326 -119.72036) (xy -1.95326 -120.10136) (xy -2.46126 -120.10136)
				)
			)
		)
	)
	(footprint ""
		(layer "B.Cu")
		(at 400.177 -111.379)
		(property "Reference" "C2N5"
			(at 0 0 0)
			(layer "B.SilkS")
			(hide yes)
			(effects
				(font
					(size 1.27 1.27)
				)
				(justify mirror)
			)
		)
		(property "Value" ""
			(at 0 0 0)
			(layer "B.Fab")
			(effects
				(font
					(size 1.27 1.27)
				)
				(justify mirror)
			)
		)
		(duplicate_pad_numbers_are_jumpers no)
		(fp_poly
			(pts
				(xy -0.3048 -0.1016) (xy -0.3048 0.9906) (xy 0.3048 0.9906) (xy 0.3048 -0.1016)
			)
			(stroke
				(width 0)
				(type default)
			)
			(fill no)
			(layer "B.CrtYd")
		)
		(fp_line
			(start -0.3048 -0.1016)
			(end 0.3048 -0.1016)
			(stroke
				(width 0.1)
				(type default)
			)
			(layer "B.Fab")
		)
		(fp_line
			(start -0.3048 0.9906)
			(end -0.3048 -0.1016)
			(stroke
				(width 0.1)
				(type default)
			)
			(layer "B.Fab")
		)
		(fp_line
			(start 0.3048 -0.1016)
			(end 0.3048 0.9906)
			(stroke
				(width 0.1)
				(type default)
			)
			(layer "B.Fab")
		)
		(fp_line
			(start 0.3048 0.9906)
			(end -0.3048 0.9906)
			(stroke
				(width 0.1)
				(type default)
			)
			(layer "B.Fab")
		)
		(pad "1" smd rect
			(at 0 0 180)
			(size 0.508 0.508)
			(layers "B.Cu" "B.Mask" "B.Paste")
			(net "P1V05_PCH_STBY_KR_PLL")
		)
		(pad "2" smd rect
			(at 0 0.889 180)
			(size 0.508 0.508)
			(layers "B.Cu" "B.Mask" "B.Paste")
			(net "GND")
		)
		(zone
			(layer "B.Cu")
			(hatch none 0.5)
			(connect_pads
				(clearance 0)
			)
			(min_thickness 0.25)
			(keepout
				(tracks allowed)
				(vias not_allowed)
				(pads allowed)
				(copperpour not_allowed)
				(footprints allowed)
			)
			(placement
				(enabled no)
				(sheetname "")
			)
			(fill
				(thermal_gap 0.5)
				(thermal_bridge_width 0.5)
				(island_removal_mode 0)
			)
			(polygon
				(pts
					(xy 400.431 -111.125) (xy 399.923 -111.125) (xy 399.923 -110.744) (xy 400.431 -110.744)
				)
			)
		)
		(zone
			(layer "B.Cu")
			(hatch none 0.5)
			(connect_pads
				(clearance 0)
			)
			(min_thickness 0.25)
			(keepout
				(tracks not_allowed)
				(vias allowed)
				(pads allowed)
				(copperpour not_allowed)
				(footprints allowed)
			)
			(placement
				(enabled no)
				(sheetname "")
			)
			(fill
				(thermal_gap 0.5)
				(thermal_bridge_width 0.5)
				(island_removal_mode 0)
			)
			(polygon
				(pts
					(xy 400.431 -110.744) (xy 399.923 -110.744) (xy 399.923 -111.125) (xy 400.431 -111.125)
				)
			)
		)
	)
	(footprint ""
		(layer "B.Cu")
		(at 197.848728 -67.978782 90)
		(property "Reference" "C6P22"
			(at 0 0 90)
			(layer "B.SilkS")
			(hide yes)
			(effects
				(font
					(size 1.27 1.27)
				)
				(justify mirror)
			)
		)
		(property "Value" ""
			(at 0 0 90)
			(layer "B.Fab")
			(effects
				(font
					(size 1.27 1.27)
				)
				(justify mirror)
			)
		)
		(duplicate_pad_numbers_are_jumpers no)
		(fp_rect
			(start -0.7239 -0.2159)
			(end 0.7239 1.9939)
			(stroke
				(width 0)
				(type default)
			)
			(fill no)
			(layer "B.CrtYd")
		)
		(fp_line
			(start 0.7239 -0.2159)
			(end 0.7239 1.9939)
			(stroke
				(width 0.1)
				(type default)
			)
			(layer "B.Fab")
		)
		(fp_line
			(start -0.7239 -0.2159)
			(end 0.7239 -0.2159)
			(stroke
				(width 0.1)
				(type default)
			)
			(layer "B.Fab")
		)
		(fp_line
			(start 0.7239 1.9939)
			(end -0.7239 1.9939)
			(stroke
				(width 0.1)
				(type default)
			)
			(layer "B.Fab")
		)
		(fp_line
			(start -0.7239 1.9939)
			(end -0.7239 -0.2159)
			(stroke
				(width 0.1)
				(type default)
			)
			(layer "B.Fab")
		)
		(pad "1" smd rect
			(at 0 0 270)
			(size 1.27 1.016)
			(layers "B.Cu" "B.Mask" "B.Paste")
			(net "VR_FET_SW_P12V_STBY_PVCCIN_CPU0")
		)
		(pad "2" smd rect
			(at 0 1.778 270)
			(size 1.27 1.016)
			(layers "B.Cu" "B.Mask" "B.Paste")
			(net "GND")
		)
		(zone
			(layer "B.Cu")
			(hatch none 0.5)
			(connect_pads
				(clearance 0)
			)
			(min_thickness 0.25)
			(keepout
				(tracks not_allowed)
				(vias allowed)
				(pads allowed)
				(copperpour not_allowed)
				(footprints allowed)
			)
			(placement
				(enabled no)
				(sheetname "")
			)
			(fill
				(thermal_gap 0.5)
				(thermal_bridge_width 0.5)
				(island_removal_mode 0)
			)
			(polygon
				(pts
					(xy 198.356728 -67.343782) (xy 199.118728 -67.343782) (xy 199.118728 -68.613782) (xy 198.356728 -68.613782)
				)
			)
		)
	)
	(footprint ""
		(layer "B.Cu")
		(at 420.624 -154.94 90)
		(property "Reference" "C2L4"
			(at 0 0 90)
			(layer "B.SilkS")
			(hide yes)
			(effects
				(font
					(size 1.27 1.27)
				)
				(justify mirror)
			)
		)
		(property "Value" ""
			(at 0 0 90)
			(layer "B.Fab")
			(effects
				(font
					(size 1.27 1.27)
				)
				(justify mirror)
			)
		)
		(duplicate_pad_numbers_are_jumpers no)
		(fp_poly
			(pts
				(xy -0.3048 -0.1016) (xy -0.3048 0.9906) (xy 0.3048 0.9906) (xy 0.3048 -0.1016)
			)
			(stroke
				(width 0)
				(type default)
			)
			(fill no)
			(layer "B.CrtYd")
		)
		(fp_line
			(start 0.3048 -0.1016)
			(end 0.3048 0.9906)
			(stroke
				(width 0.1)
				(type default)
			)
			(layer "B.Fab")
		)
		(fp_line
			(start -0.3048 -0.1016)
			(end 0.3048 -0.1016)
			(stroke
				(width 0.1)
				(type default)
			)
			(layer "B.Fab")
		)
		(fp_line
			(start 0.3048 0.9906)
			(end -0.3048 0.9906)
			(stroke
				(width 0.1)
				(type default)
			)
			(layer "B.Fab")
		)
		(fp_line
			(start -0.3048 0.9906)
			(end -0.3048 -0.1016)
			(stroke
				(width 0.1)
				(type default)
			)
			(layer "B.Fab")
		)
		(pad "1" smd rect
			(at 0 0 270)
			(size 0.508 0.508)
			(layers "B.Cu" "B.Mask" "B.Paste")
			(net "SATA6G_PCH_PCIE_UP_SATA_RXP<3>")
		)
		(pad "2" smd rect
			(at 0 0.889 270)
			(size 0.508 0.508)
			(layers "B.Cu" "B.Mask" "B.Paste")
			(net "SATA6G_P3_RX_C_DP")
		)
		(zone
			(layer "B.Cu")
			(hatch none 0.5)
			(connect_pads
				(clearance 0)
			)
			(min_thickness 0.25)
			(keepout
				(tracks allowed)
				(vias not_allowed)
				(pads allowed)
				(copperpour not_allowed)
				(footprints allowed)
			)
			(placement
				(enabled no)
				(sheetname "")
			)
			(fill
				(thermal_gap 0.5)
				(thermal_bridge_width 0.5)
				(island_removal_mode 0)
			)
			(polygon
				(pts
					(xy 420.878 -155.194) (xy 420.878 -154.686) (xy 421.259 -154.686) (xy 421.259 -155.194)
				)
			)
		)
		(zone
			(layer "B.Cu")
			(hatch none 0.5)
			(connect_pads
				(clearance 0)
			)
			(min_thickness 0.25)
			(keepout
				(tracks not_allowed)
				(vias allowed)
				(pads allowed)
				(copperpour not_allowed)
				(footprints allowed)
			)
			(placement
				(enabled no)
				(sheetname "")
			)
			(fill
				(thermal_gap 0.5)
				(thermal_bridge_width 0.5)
				(island_removal_mode 0)
			)
			(polygon
				(pts
					(xy 421.259 -155.194) (xy 421.259 -154.686) (xy 420.878 -154.686) (xy 420.878 -155.194)
				)
			)
		)
	)
	(footprint ""
		(layer "B.Cu")
		(at 336.042 -104.394 90)
		(property "Reference" "C3N26"
			(at 1.24333 -3.81 0)
			(unlocked yes)
			(layer "B.SilkS")
			(effects
				(font
					(size 0.7874 0.5842)
					(thickness 0.1524)
				)
				(justify mirror)
			)
		)
		(property "Value" ""
			(at 0 0 90)
			(layer "B.Fab")
			(effects
				(font
					(size 1.27 1.27)
				)
				(justify mirror)
			)
		)
		(duplicate_pad_numbers_are_jumpers no)
		(fp_line
			(start 2.563114 -1.616456)
			(end 2.563114 1.633728)
			(stroke
				(width 0.1524)
				(type default)
			)
			(layer "B.SilkS")
		)
		(fp_line
			(start 1.6002 -1.616456)
			(end 2.563114 -1.616456)
			(stroke
				(width 0.1524)
				(type default)
			)
			(layer "B.SilkS")
		)
		(fp_line
			(start -1.6002 -1.616456)
			(end -2.504948 -1.616456)
			(stroke
				(width 0.1524)
				(type default)
			)
			(layer "B.SilkS")
		)
		(fp_line
			(start -2.504948 -1.616456)
			(end -2.504948 1.633728)
			(stroke
				(width 0.1524)
				(type default)
			)
			(layer "B.SilkS")
		)
		(fp_line
			(start 2.563114 1.633728)
			(end 1.6002 1.633728)
			(stroke
				(width 0.1524)
				(type default)
			)
			(layer "B.SilkS")
		)
		(fp_line
			(start -2.504948 1.633728)
			(end -1.6002 1.633728)
			(stroke
				(width 0.1524)
				(type default)
			)
			(layer "B.SilkS")
		)
		(fp_line
			(start 2.286 7.366)
			(end 2.286 1.632712)
			(stroke
				(width 0.1524)
				(type default)
			)
			(layer "B.SilkS")
		)
		(fp_line
			(start 2.286 7.366)
			(end 1.60147 7.366)
			(stroke
				(width 0.1524)
				(type default)
			)
			(layer "B.SilkS")
		)
		(fp_line
			(start -2.286 7.366)
			(end -2.286 1.63195)
			(stroke
				(width 0.1524)
				(type default)
			)
			(layer "B.SilkS")
		)
		(fp_line
			(start -2.286 7.366)
			(end -1.600708 7.366)
			(stroke
				(width 0.1524)
				(type default)
			)
			(layer "B.SilkS")
		)
		(fp_rect
			(start 2.286 7.366)
			(end -2.286 -0.254)
			(stroke
				(width 0)
				(type default)
			)
			(fill no)
			(layer "B.CrtYd")
		)
		(fp_line
			(start 2.286 -0.254)
			(end -2.286 -0.254)
			(stroke
				(width 0.1)
				(type default)
			)
			(layer "B.Fab")
		)
		(fp_line
			(start -2.286 -0.254)
			(end -2.286 7.366)
			(stroke
				(width 0.1)
				(type default)
			)
			(layer "B.Fab")
		)
		(fp_line
			(start 2.286 7.366)
			(end 2.286 -0.254)
			(stroke
				(width 0.1)
				(type default)
			)
			(layer "B.Fab")
		)
		(fp_line
			(start -2.286 7.366)
			(end 2.286 7.366)
			(stroke
				(width 0.1)
				(type default)
			)
			(layer "B.Fab")
		)
		(pad "1" smd rect
			(at 0 0 270)
			(size 2.54 3.048)
			(layers "B.Cu" "B.Mask" "B.Paste")
			(net "PVCCIO_CPU0")
		)
		(pad "2" smd rect
			(at 0 7.112 270)
			(size 2.54 3.048)
			(layers "B.Cu" "B.Mask" "B.Paste")
			(net "GND")
		)
	)
	(footprint ""
		(layer "B.Cu")
		(at 368.184938 -102.18039 -90)
		(property "Reference" "C3N31"
			(at 0 0 90)
			(layer "B.SilkS")
			(hide yes)
			(effects
				(font
					(size 1.27 1.27)
				)
				(justify mirror)
			)
		)
		(property "Value" ""
			(at 0 0 90)
			(layer "B.Fab")
			(effects
				(font
					(size 1.27 1.27)
				)
				(justify mirror)
			)
		)
		(duplicate_pad_numbers_are_jumpers no)
		(fp_poly
			(pts
				(xy 0.4953 -0.2032) (xy -0.4953 -0.2032) (xy -0.4953 1.6002) (xy 0.4953 1.6002)
			)
			(stroke
				(width 0)
				(type default)
			)
			(fill no)
			(layer "B.CrtYd")
		)
		(fp_line
			(start -0.4953 1.6002)
			(end 0.4953 1.6002)
			(stroke
				(width 0.1)
				(type default)
			)
			(layer "B.Fab")
		)
		(fp_line
			(start 0.4953 1.6002)
			(end 0.4953 -0.2032)
			(stroke
				(width 0.1)
				(type default)
			)
			(layer "B.Fab")
		)
		(fp_line
			(start -0.4953 -0.2032)
			(end -0.4953 1.6002)
			(stroke
				(width 0.1)
				(type default)
			)
			(layer "B.Fab")
		)
		(fp_line
			(start 0.4953 -0.2032)
			(end -0.4953 -0.2032)
			(stroke
				(width 0.1)
				(type default)
			)
			(layer "B.Fab")
		)
		(pad "1" smd rect
			(at 0 0 90)
			(size 0.762 0.889)
			(layers "B.Cu" "B.Mask" "B.Paste")
			(net "PVNN_PCH_STBY")
		)
		(pad "2" smd rect
			(at 0 1.397 90)
			(size 0.762 0.889)
			(layers "B.Cu" "B.Mask" "B.Paste")
			(net "GND")
		)
		(zone
			(layer "B.Cu")
			(hatch none 0.5)
			(connect_pads
				(clearance 0)
			)
			(min_thickness 0.25)
			(keepout
				(tracks not_allowed)
				(vias allowed)
				(pads allowed)
				(copperpour not_allowed)
				(footprints allowed)
			)
			(placement
				(enabled no)
				(sheetname "")
			)
			(fill
				(thermal_gap 0.5)
				(thermal_bridge_width 0.5)
				(island_removal_mode 0)
			)
			(polygon
				(pts
					(xy 367.740438 -101.79939) (xy 367.740438 -102.56139) (xy 367.232438 -102.56139) (xy 367.232438 -101.79939)
				)
			)
		)
	)
	(footprint ""
		(layer "B.Cu")
		(at 438.833006 -41.648126 180)
		(property "Reference" "R25W10"
			(at 0 0 0)
			(layer "B.SilkS")
			(hide yes)
			(effects
				(font
					(size 1.27 1.27)
				)
				(justify mirror)
			)
		)
		(property "Value" "*"
			(at -0.064008 -4.108196 180)
			(unlocked yes)
			(layer "B.Fab")
			(hide yes)
			(effects
				(font
					(size 1.27 1.016)
					(thickness 0.1524)
				)
				(justify mirror)
			)
		)
		(property "Device Type" "120R2F-GP_RCL_GP-120R2F-GP,64.A"
			(at -0.064008 -5.632196 180)
			(unlocked yes)
			(layer "B.Fab")
			(hide yes)
			(effects
				(font
					(size 1.27 1.016)
					(thickness 0.1524)
				)
				(justify mirror)
			)
		)
		(duplicate_pad_numbers_are_jumpers no)
		(fp_line
			(start 0.508 -0.9398)
			(end 0.508 0.9398)
			(stroke
				(width 0.1524)
				(type default)
			)
			(layer "B.SilkS")
		)
		(fp_line
			(start -0.508 -0.9398)
			(end 0.508 -0.9398)
			(stroke
				(width 0.1524)
				(type default)
			)
			(layer "B.SilkS")
		)
		(fp_rect
			(start 0.508 0.9398)
			(end -0.508 -0.9398)
			(stroke
				(width 0)
				(type default)
			)
			(fill no)
			(layer "B.CrtYd")
		)
		(fp_rect
			(start 0.508 0.9398)
			(end -0.508 -0.9398)
			(stroke
				(width 0)
				(type default)
			)
			(fill no)
			(layer "B.Fab")
		)
		(pad "1" smd custom
			(at 0 -0.4445)
			(size 0.1397 0.1397)
			(layers "B.Cu" "B.Mask" "B.Paste")
			(net "GND")
			(options
				(clearance outline)
				(anchor circle)
			)
			(primitives
				(gr_poly
					(pts
						(arc
							(start -0.1778 0.2794)
							(mid -0.249642 0.249642)
							(end -0.2794 0.1778)
						)
						(arc
							(start -0.2794 -0.1778)
							(mid -0.249642 -0.249642)
							(end -0.1778 -0.2794)
						)
						(arc
							(start 0.1778 -0.2794)
							(mid 0.249642 -0.249642)
							(end 0.2794 -0.1778)
						)
						(arc
							(start 0.2794 0.1778)
							(mid 0.249642 0.249642)
							(end 0.1778 0.2794)
						)
					)
					(width 0)
					(fill yes)
				)
			)
		)
		(pad "2" smd custom
			(at 0 0.4445)
			(size 0.1397 0.1397)
			(layers "B.Cu" "B.Mask" "B.Paste")
			(net "BMC_M_BA1")
			(options
				(clearance outline)
				(anchor circle)
			)
			(primitives
				(gr_poly
					(pts
						(arc
							(start -0.1778 0.2794)
							(mid -0.249642 0.249642)
							(end -0.2794 0.1778)
						)
						(arc
							(start -0.2794 -0.1778)
							(mid -0.249642 -0.249642)
							(end -0.1778 -0.2794)
						)
						(arc
							(start 0.1778 -0.2794)
							(mid 0.249642 -0.249642)
							(end 0.2794 -0.1778)
						)
						(arc
							(start 0.2794 0.1778)
							(mid 0.249642 0.249642)
							(end 0.1778 0.2794)
						)
					)
					(width 0)
					(fill yes)
				)
			)
		)
	)
)
